(kicad_pcb
	(version 20260206)
	(generator "pcbnew")
	(generator_version "10.0")
	(general
		(thickness 1.6)
		(legacy_teardrops no)
	)
	(paper "A4")
	(title_block
		(title "Wiwynn_Tioga_Pass_MB.brd")
		(comment 1 "Tioga Pass / footprints 3894-3899 of 4770")
	)
	(layers
		(0 "F.Cu" signal "TOP")
		(4 "In1.Cu" signal "L2GND")
		(6 "In2.Cu" signal "L3")
		(8 "In3.Cu" signal "L4GND")
		(10 "In4.Cu" signal "L5")
		(12 "In5.Cu" signal "L6GND")
		(14 "In6.Cu" signal "L7VCC")
		(16 "In7.Cu" signal "L8VCC")
		(18 "In8.Cu" signal "L9GND")
		(20 "In9.Cu" signal "L10")
		(22 "In10.Cu" signal "L11GND")
		(24 "In11.Cu" signal "L12")
		(26 "In12.Cu" signal "L13GND")
		(2 "B.Cu" signal "BOTTOM")
		(9 "F.Adhes" user "F.Adhesive")
		(11 "B.Adhes" user "B.Adhesive")
		(13 "F.Paste" user "Package Geometry/Pastemask Top")
		(15 "B.Paste" user "Package Geometry/Pastemask Bottom")
		(5 "F.SilkS" user "Ref Des/Silkscreen Top")
		(7 "B.SilkS" user "Ref Des/Silkscreen Bottom")
		(1 "F.Mask" user "Board Geometry/Soldermask Top")
		(3 "B.Mask" user "Board Geometry/Soldermask Bottom")
		(17 "Dwgs.User" user "User.Drawings")
		(19 "Cmts.User" user "User.Comments")
		(21 "Eco1.User" user "User.Eco1")
		(23 "Eco2.User" user "User.Eco2")
		(25 "Edge.Cuts" user "Board Geometry/Outline")
		(27 "Margin" user)
		(31 "F.CrtYd" user "Package Geometry/Place Bound Top")
		(29 "B.CrtYd" user "Package Geometry/Place Bound Bottom")
		(35 "F.Fab" user "Ref Des/Assembly Top")
		(33 "B.Fab" user "Ref Des/Assembly Bottom")
	)
	(footprint ""
		(layer "B.Cu")
		(at 374.74271 -75.492864 180)
		(property "Reference" "C3R1"
			(at 0 0 0)
			(layer "B.SilkS")
			(hide yes)
			(effects
				(font
					(size 1.27 1.27)
				)
				(justify mirror)
			)
		)
		(property "Value" ""
			(at 0 0 0)
			(layer "B.Fab")
			(effects
				(font
					(size 1.27 1.27)
				)
				(justify mirror)
			)
		)
		(duplicate_pad_numbers_are_jumpers no)
		(fp_rect
			(start 0.2794 0.9144)
			(end -0.2794 -0.1143)
			(stroke
				(width 0)
				(type default)
			)
			(fill no)
			(layer "B.CrtYd")
		)
		(fp_line
			(start 0.2794 0.9144)
			(end 0.2794 -0.1143)
			(stroke
				(width 0.1)
				(type default)
			)
			(layer "B.Fab")
		)
		(fp_line
			(start 0.2794 -0.1143)
			(end -0.2794 -0.1143)
			(stroke
				(width 0.1)
				(type default)
			)
			(layer "B.Fab")
		)
		(fp_line
			(start -0.2794 0.9144)
			(end 0.2794 0.9144)
			(stroke
				(width 0.1)
				(type default)
			)
			(layer "B.Fab")
		)
		(fp_line
			(start -0.2794 -0.1143)
			(end -0.2794 0.9144)
			(stroke
				(width 0.1)
				(type default)
			)
			(layer "B.Fab")
		)
		(pad "1" smd custom
			(at 0 0 90)
			(size 0.10414 0.10414)
			(layers "B.Cu" "B.Mask" "B.Paste")
			(net "P3V3_STBY")
			(options
				(clearance outline)
				(anchor circle)
			)
			(primitives
				(gr_poly
					(pts
						(xy -0.20828 -0.08636) (xy -0.20828 0.08636) (xy -0.08636 0.20828) (xy 0.086614 0.20828) (xy 0.20828 0.086614)
						(xy 0.20828 -0.08636) (xy 0.08636 -0.20828) (xy -0.08636 -0.20828)
					)
					(width 0)
					(fill yes)
				)
			)
		)
		(pad "2" smd custom
			(at 0 0.8001 90)
			(size 0.10414 0.10414)
			(layers "B.Cu" "B.Mask" "B.Paste")
			(net "GND")
			(options
				(clearance outline)
				(anchor circle)
			)
			(primitives
				(gr_poly
					(pts
						(xy -0.20828 -0.08636) (xy -0.20828 0.08636) (xy -0.08636 0.20828) (xy 0.086614 0.20828) (xy 0.20828 0.086614)
						(xy 0.20828 -0.08636) (xy 0.08636 -0.20828) (xy -0.08636 -0.20828)
					)
					(width 0)
					(fill yes)
				)
			)
		)
		(zone
			(layer "B.Cu")
			(hatch none 0.5)
			(connect_pads
				(clearance 0)
			)
			(min_thickness 0.25)
			(keepout
				(tracks allowed)
				(vias not_allowed)
				(pads allowed)
				(copperpour not_allowed)
				(footprints allowed)
			)
			(placement
				(enabled no)
				(sheetname "")
			)
			(fill
				(thermal_gap 0.5)
				(thermal_bridge_width 0.5)
				(island_removal_mode 0)
			)
			(polygon
				(pts
					(xy 374.65508 -75.702414) (xy 374.65508 -76.083414) (xy 374.83034 -76.083414) (xy 374.830594 -75.702414)
				)
			)
		)
		(zone
			(layer "B.Cu")
			(hatch none 0.5)
			(connect_pads
				(clearance 0)
			)
			(min_thickness 0.25)
			(keepout
				(tracks not_allowed)
				(vias allowed)
				(pads allowed)
				(copperpour not_allowed)
				(footprints allowed)
			)
			(placement
				(enabled no)
				(sheetname "")
			)
			(fill
				(thermal_gap 0.5)
				(thermal_bridge_width 0.5)
				(island_removal_mode 0)
			)
			(polygon
				(pts
					(xy 374.65508 -75.702414) (xy 374.65508 -76.083414) (xy 374.83034 -76.083414) (xy 374.830594 -75.702414)
				)
			)
		)
	)
	(footprint ""
		(layer "B.Cu")
		(at 269.559532 -135.4074 90)
		(property "Reference" "C5M2"
			(at -1.848866 0.752348 90)
			(unlocked yes)
			(layer "B.SilkS")
			(effects
				(font
					(size 1.27 0.9652)
					(thickness 0.1524)
				)
				(justify mirror)
			)
		)
		(property "Value" ""
			(at 0 0 90)
			(layer "B.Fab")
			(effects
				(font
					(size 1.27 1.27)
				)
				(justify mirror)
			)
		)
		(duplicate_pad_numbers_are_jumpers no)
		(fp_rect
			(start 0.500126 1.598422)
			(end -0.500126 -0.201422)
			(stroke
				(width 0)
				(type default)
			)
			(fill no)
			(layer "B.CrtYd")
		)
		(fp_line
			(start 0.500126 -0.201422)
			(end -0.500126 -0.201422)
			(stroke
				(width 0.1)
				(type default)
			)
			(layer "B.Fab")
		)
		(fp_line
			(start -0.500126 -0.201422)
			(end -0.500126 1.598422)
			(stroke
				(width 0.1)
				(type default)
			)
			(layer "B.Fab")
		)
		(fp_line
			(start 0.500126 1.598422)
			(end 0.500126 -0.201422)
			(stroke
				(width 0.1)
				(type default)
			)
			(layer "B.Fab")
		)
		(fp_line
			(start -0.500126 1.598422)
			(end 0.500126 1.598422)
			(stroke
				(width 0.1)
				(type default)
			)
			(layer "B.Fab")
		)
		(pad "1" smd rect
			(at 0 0)
			(size 0.889 0.9906)
			(layers "B.Cu" "B.Mask" "B.Paste")
			(net "PVDDQ_DEF")
		)
		(pad "2" smd rect
			(at 0 1.397)
			(size 0.889 0.9906)
			(layers "B.Cu" "B.Mask" "B.Paste")
			(net "GND")
		)
		(zone
			(layer "B.Cu")
			(hatch none 0.5)
			(connect_pads
				(clearance 0)
			)
			(min_thickness 0.25)
			(keepout
				(tracks not_allowed)
				(vias allowed)
				(pads allowed)
				(copperpour not_allowed)
				(footprints allowed)
			)
			(placement
				(enabled no)
				(sheetname "")
			)
			(fill
				(thermal_gap 0.5)
				(thermal_bridge_width 0.5)
				(island_removal_mode 0)
			)
			(polygon
				(pts
					(xy 270.512032 -135.9027) (xy 270.004032 -135.9027) (xy 270.004032 -134.9121) (xy 270.512032 -134.9121)
				)
			)
		)
		(zone
			(layer "B.Cu")
			(hatch none 0.5)
			(connect_pads
				(clearance 0)
			)
			(min_thickness 0.25)
			(keepout
				(tracks allowed)
				(vias not_allowed)
				(pads allowed)
				(copperpour not_allowed)
				(footprints allowed)
			)
			(placement
				(enabled no)
				(sheetname "")
			)
			(fill
				(thermal_gap 0.5)
				(thermal_bridge_width 0.5)
				(island_removal_mode 0)
			)
			(polygon
				(pts
					(xy 270.512032 -135.9027) (xy 270.004032 -135.9027) (xy 270.004032 -134.9121) (xy 270.512032 -134.9121)
				)
			)
		)
	)
	(footprint ""
		(layer "B.Cu")
		(at 451.9422 -129.9464)
		(property "Reference" "C1M33"
			(at 0 0 0)
			(layer "B.SilkS")
			(hide yes)
			(effects
				(font
					(size 1.27 1.27)
				)
				(justify mirror)
			)
		)
		(property "Value" ""
			(at 0 0 0)
			(layer "B.Fab")
			(effects
				(font
					(size 1.27 1.27)
				)
				(justify mirror)
			)
		)
		(duplicate_pad_numbers_are_jumpers no)
		(fp_poly
			(pts
				(xy -0.3048 -0.1016) (xy -0.3048 0.9906) (xy 0.3048 0.9906) (xy 0.3048 -0.1016)
			)
			(stroke
				(width 0)
				(type default)
			)
			(fill no)
			(layer "B.CrtYd")
		)
		(fp_line
			(start -0.3048 -0.1016)
			(end 0.3048 -0.1016)
			(stroke
				(width 0.1)
				(type default)
			)
			(layer "B.Fab")
		)
		(fp_line
			(start -0.3048 0.9906)
			(end -0.3048 -0.1016)
			(stroke
				(width 0.1)
				(type default)
			)
			(layer "B.Fab")
		)
		(fp_line
			(start 0.3048 -0.1016)
			(end 0.3048 0.9906)
			(stroke
				(width 0.1)
				(type default)
			)
			(layer "B.Fab")
		)
		(fp_line
			(start 0.3048 0.9906)
			(end -0.3048 0.9906)
			(stroke
				(width 0.1)
				(type default)
			)
			(layer "B.Fab")
		)
		(pad "1" smd rect
			(at 0 0 180)
			(size 0.508 0.508)
			(layers "B.Cu" "B.Mask" "B.Paste")
			(net "JTAG_MCP_TMS_R1")
		)
		(pad "2" smd rect
			(at 0 0.889 180)
			(size 0.508 0.508)
			(layers "B.Cu" "B.Mask" "B.Paste")
			(net "GND")
		)
		(zone
			(layer "B.Cu")
			(hatch none 0.5)
			(connect_pads
				(clearance 0)
			)
			(min_thickness 0.25)
			(keepout
				(tracks allowed)
				(vias not_allowed)
				(pads allowed)
				(copperpour not_allowed)
				(footprints allowed)
			)
			(placement
				(enabled no)
				(sheetname "")
			)
			(fill
				(thermal_gap 0.5)
				(thermal_bridge_width 0.5)
				(island_removal_mode 0)
			)
			(polygon
				(pts
					(xy 452.1962 -129.6924) (xy 451.6882 -129.6924) (xy 451.6882 -129.3114) (xy 452.1962 -129.3114)
				)
			)
		)
		(zone
			(layer "B.Cu")
			(hatch none 0.5)
			(connect_pads
				(clearance 0)
			)
			(min_thickness 0.25)
			(keepout
				(tracks not_allowed)
				(vias allowed)
				(pads allowed)
				(copperpour not_allowed)
				(footprints allowed)
			)
			(placement
				(enabled no)
				(sheetname "")
			)
			(fill
				(thermal_gap 0.5)
				(thermal_bridge_width 0.5)
				(island_removal_mode 0)
			)
			(polygon
				(pts
					(xy 452.1962 -129.3114) (xy 451.6882 -129.3114) (xy 451.6882 -129.6924) (xy 452.1962 -129.6924)
				)
			)
		)
	)
	(footprint ""
		(layer "B.Cu")
		(at 491.07344 -123.56592 -90)
		(property "Reference" "R9B6"
			(at 0 0 90)
			(layer "B.SilkS")
			(hide yes)
			(effects
				(font
					(size 1.27 1.27)
				)
				(justify mirror)
			)
		)
		(property "Value" ""
			(at 0 0 90)
			(layer "B.Fab")
			(effects
				(font
					(size 1.27 1.27)
				)
				(justify mirror)
			)
		)
		(duplicate_pad_numbers_are_jumpers no)
		(fp_rect
			(start 0.2794 -0.1016)
			(end -0.2794 0.9906)
			(stroke
				(width 0)
				(type default)
			)
			(fill no)
			(layer "B.CrtYd")
		)
		(fp_line
			(start -0.2794 0.9906)
			(end -0.2794 -0.1016)
			(stroke
				(width 0.1)
				(type default)
			)
			(layer "B.Fab")
		)
		(fp_line
			(start 0.2794 0.9906)
			(end -0.2794 0.9906)
			(stroke
				(width 0.1)
				(type default)
			)
			(layer "B.Fab")
		)
		(fp_line
			(start -0.2794 -0.1016)
			(end 0.2794 -0.1016)
			(stroke
				(width 0.1)
				(type default)
			)
			(layer "B.Fab")
		)
		(fp_line
			(start 0.2794 -0.1016)
			(end 0.2794 0.9906)
			(stroke
				(width 0.1)
				(type default)
			)
			(layer "B.Fab")
		)
		(pad "1" smd rect
			(at 0 0 90)
			(size 0.508 0.508)
			(layers "B.Cu" "B.Mask" "B.Paste")
			(net "P3V3_STBY")
		)
		(pad "2" smd rect
			(at 0 0.889 90)
			(size 0.508 0.508)
			(layers "B.Cu" "B.Mask" "B.Paste")
			(net "PU_TMP421_1_A1")
		)
		(zone
			(layer "B.Cu")
			(hatch none 0.5)
			(connect_pads
				(clearance 0)
			)
			(min_thickness 0.25)
			(keepout
				(tracks not_allowed)
				(vias allowed)
				(pads allowed)
				(copperpour not_allowed)
				(footprints allowed)
			)
			(placement
				(enabled no)
				(sheetname "")
			)
			(fill
				(thermal_gap 0.5)
				(thermal_bridge_width 0.5)
				(island_removal_mode 0)
			)
			(polygon
				(pts
					(xy 490.81944 -123.31192) (xy 490.81944 -123.81992) (xy 490.43844 -123.81992) (xy 490.43844 -123.31192)
				)
			)
		)
		(zone
			(layer "B.Cu")
			(hatch none 0.5)
			(connect_pads
				(clearance 0)
			)
			(min_thickness 0.25)
			(keepout
				(tracks allowed)
				(vias not_allowed)
				(pads allowed)
				(copperpour not_allowed)
				(footprints allowed)
			)
			(placement
				(enabled no)
				(sheetname "")
			)
			(fill
				(thermal_gap 0.5)
				(thermal_bridge_width 0.5)
				(island_removal_mode 0)
			)
			(polygon
				(pts
					(xy 490.81944 -123.31192) (xy 490.81944 -123.81992) (xy 490.43844 -123.81992) (xy 490.43844 -123.31192)
				)
			)
		)
	)
	(footprint ""
		(layer "B.Cu")
		(at 387.75894 -85.51672 90)
		(property "Reference" "R8D16"
			(at 0.8382 -0.67818 90)
			(unlocked yes)
			(layer "B.SilkS")
			(effects
				(font
					(size 0.4064 0.254)
					(thickness 0.1524)
				)
				(justify left mirror)
			)
		)
		(property "Value" ""
			(at 0 0 90)
			(layer "B.Fab")
			(effects
				(font
					(size 1.27 1.27)
				)
				(justify mirror)
			)
		)
		(duplicate_pad_numbers_are_jumpers no)
		(fp_poly
			(pts
				(xy 0.2794 -0.1016) (xy -0.2794 -0.1016) (xy -0.2794 0.9906) (xy 0.2794 0.9906)
			)
			(stroke
				(width 0)
				(type default)
			)
			(fill no)
			(layer "B.CrtYd")
		)
		(fp_line
			(start 0.2794 -0.1016)
			(end 0.2794 0.9906)
			(stroke
				(width 0.1)
				(type default)
			)
			(layer "B.Fab")
		)
		(fp_line
			(start -0.2794 -0.1016)
			(end 0.2794 -0.1016)
			(stroke
				(width 0.1)
				(type default)
			)
			(layer "B.Fab")
		)
		(fp_line
			(start 0.2794 0.9906)
			(end -0.2794 0.9906)
			(stroke
				(width 0.1)
				(type default)
			)
			(layer "B.Fab")
		)
		(fp_line
			(start -0.2794 0.9906)
			(end -0.2794 -0.1016)
			(stroke
				(width 0.1)
				(type default)
			)
			(layer "B.Fab")
		)
		(pad "1" smd rect
			(at 0 0 270)
			(size 0.508 0.508)
			(layers "B.Cu" "B.Mask" "B.Paste")
			(net "P3V3_STBY")
		)
		(pad "2" smd rect
			(at 0 0.889 270)
			(size 0.508 0.508)
			(layers "B.Cu" "B.Mask" "B.Paste")
			(net "RMII_PCH_SPRNGVLLE_ARB_OUT")
		)
		(zone
			(layer "B.Cu")
			(hatch none 0.5)
			(connect_pads
				(clearance 0)
			)
			(min_thickness 0.25)
			(keepout
				(tracks allowed)
				(vias not_allowed)
				(pads allowed)
				(copperpour not_allowed)
				(footprints allowed)
			)
			(placement
				(enabled no)
				(sheetname "")
			)
			(fill
				(thermal_gap 0.5)
				(thermal_bridge_width 0.5)
				(island_removal_mode 0)
			)
			(polygon
				(pts
					(xy 388.01294 -85.77072) (xy 388.01294 -85.26272) (xy 388.39394 -85.26272) (xy 388.39394 -85.77072)
				)
			)
		)
		(zone
			(layer "B.Cu")
			(hatch none 0.5)
			(connect_pads
				(clearance 0)
			)
			(min_thickness 0.25)
			(keepout
				(tracks not_allowed)
				(vias allowed)
				(pads allowed)
				(copperpour not_allowed)
				(footprints allowed)
			)
			(placement
				(enabled no)
				(sheetname "")
			)
			(fill
				(thermal_gap 0.5)
				(thermal_bridge_width 0.5)
				(island_removal_mode 0)
			)
			(polygon
				(pts
					(xy 388.39394 -85.77072) (xy 388.39394 -85.26272) (xy 388.01294 -85.26272) (xy 388.01294 -85.77072)
				)
			)
		)
	)
	(footprint ""
		(layer "B.Cu")
		(at 362.270294 -42.369486)
		(property "Reference" "R2T65"
			(at 0 0 0)
			(layer "B.SilkS")
			(hide yes)
			(effects
				(font
					(size 1.27 1.27)
				)
				(justify mirror)
			)
		)
		(property "Value" ""
			(at 0 0 0)
			(layer "B.Fab")
			(effects
				(font
					(size 1.27 1.27)
				)
				(justify mirror)
			)
		)
		(duplicate_pad_numbers_are_jumpers no)
		(fp_poly
			(pts
				(xy 0.2794 -0.1016) (xy -0.2794 -0.1016) (xy -0.2794 0.9906) (xy 0.2794 0.9906)
			)
			(stroke
				(width 0)
				(type default)
			)
			(fill no)
			(layer "B.CrtYd")
		)
		(fp_line
			(start -0.2794 -0.1016)
			(end 0.2794 -0.1016)
			(stroke
				(width 0.1)
				(type default)
			)
			(layer "B.Fab")
		)
		(fp_line
			(start -0.2794 0.9906)
			(end -0.2794 -0.1016)
			(stroke
				(width 0.1)
				(type default)
			)
			(layer "B.Fab")
		)
		(fp_line
			(start 0.2794 -0.1016)
			(end 0.2794 0.9906)
			(stroke
				(width 0.1)
				(type default)
			)
			(layer "B.Fab")
		)
		(fp_line
			(start 0.2794 0.9906)
			(end -0.2794 0.9906)
			(stroke
				(width 0.1)
				(type default)
			)
			(layer "B.Fab")
		)
		(pad "1" smd rect
			(at 0 0 180)
			(size 0.508 0.508)
			(layers "B.Cu" "B.Mask" "B.Paste")
			(net "FM_CPU_ERR0_LVT3_R_N")
		)
		(pad "2" smd rect
			(at 0 0.889 180)
			(size 0.508 0.508)
			(layers "B.Cu" "B.Mask" "B.Paste")
			(net "FM_CPU_ERR0_LVT3_K_N")
		)
		(zone
			(layer "B.Cu")
			(hatch none 0.5)
			(connect_pads
				(clearance 0)
			)
			(min_thickness 0.25)
			(keepout
				(tracks allowed)
				(vias not_allowed)
				(pads allowed)
				(copperpour not_allowed)
				(footprints allowed)
			)
			(placement
				(enabled no)
				(sheetname "")
			)
			(fill
				(thermal_gap 0.5)
				(thermal_bridge_width 0.5)
				(island_removal_mode 0)
			)
			(polygon
				(pts
					(xy 362.524294 -42.115486) (xy 362.016294 -42.115486) (xy 362.016294 -41.734486) (xy 362.524294 -41.734486)
				)
			)
		)
		(zone
			(layer "B.Cu")
			(hatch none 0.5)
			(connect_pads
				(clearance 0)
			)
			(min_thickness 0.25)
			(keepout
				(tracks not_allowed)
				(vias allowed)
				(pads allowed)
				(copperpour not_allowed)
				(footprints allowed)
			)
			(placement
				(enabled no)
				(sheetname "")
			)
			(fill
				(thermal_gap 0.5)
				(thermal_bridge_width 0.5)
				(island_removal_mode 0)
			)
			(polygon
				(pts
					(xy 362.524294 -41.734486) (xy 362.016294 -41.734486) (xy 362.016294 -42.115486) (xy 362.524294 -42.115486)
				)
			)
		)
	)
)
